# T6G (Grand Teton) — schematic netlist excerpt (pin names and nets, part order shuffled) for the footprints in the layout excerpt that follows; sources: Cadence DE-HDL packaged netlist, KiCad conversion of 04192023_DAF0TMB3IC0_F0TG_MB_C_brd_V02_OCP.brd

R3087  Q_RES  130 1% CHIP  pkg 0402LF  page 255 : A = LED_PWRGD_PVDDCR_CPU0_P0_R ; B = P3V3_AUX
C156  Q_CAP  0.1UF 25V 10% X7R  pkg 0402  page 103 : A = P3V3_AUX ; B = GND

(kicad_pcb
	(version 20260206)
	(generator "pcbnew")
	(generator_version "10.0")
	(general
		(thickness 1.6)
		(legacy_teardrops no)
	)
	(paper "A4")
	(title_block
		(title "04192023_DAF0TMB3IC0_F0TG_MB_C_brd_V02_OCP.brd")
		(comment 1 "Grand Teton / footprints 5176-5177 of 8354")
	)
	(layers
		(0 "F.Cu" signal "TOP")
		(4 "In1.Cu" signal "GND")
		(6 "In2.Cu" signal "IN1")
		(8 "In3.Cu" signal "GND1")
		(10 "In4.Cu" signal "IN2")
		(12 "In5.Cu" signal "GND2")
		(14 "In6.Cu" signal "IN3")
		(16 "In7.Cu" signal "GND3")
		(18 "In8.Cu" signal "VCC")
		(20 "In9.Cu" signal "VCC1")
		(22 "In10.Cu" signal "GND4")
		(24 "In11.Cu" signal "IN4")
		(26 "In12.Cu" signal "GND5")
		(28 "In13.Cu" signal "IN5")
		(30 "In14.Cu" signal "GND6")
		(32 "In15.Cu" signal "IN6")
		(34 "In16.Cu" signal "GND7")
		(2 "B.Cu" signal "BOTTOM")
		(9 "F.Adhes" user "F.Adhesive")
		(11 "B.Adhes" user "B.Adhesive")
		(13 "F.Paste" user "Package Geometry/Pastemask Top")
		(15 "B.Paste" user "Package Geometry/Pastemask Bottom")
		(5 "F.SilkS" user "Ref Des/Silkscreen Top")
		(7 "B.SilkS" user "Ref Des/Silkscreen Bottom")
		(1 "F.Mask" user "Board Geometry/Soldermask Top")
		(3 "B.Mask" user "Board Geometry/Soldermask Bottom")
		(17 "Dwgs.User" user "User.Drawings")
		(19 "Cmts.User" user "User.Comments")
		(21 "Eco1.User" user "User.Eco1")
		(23 "Eco2.User" user "User.Eco2")
		(25 "Edge.Cuts" user "Board Geometry/Outline")
		(27 "Margin" user)
		(31 "F.CrtYd" user "Package Geometry/Place Bound Top")
		(29 "B.CrtYd" user "Package Geometry/Place Bound Bottom")
		(35 "F.Fab" user "Ref Des/Assembly Top")
		(33 "B.Fab" user "Ref Des/Assembly Bottom")
	)
	(footprint ""
		(layer "B.Cu")
		(at 324.635876 -66.708782 90)
		(property "Reference" "R3087"
			(at 0 0 90)
			(layer "B.SilkS")
			(hide yes)
			(effects
				(font
					(size 1.27 1.27)
				)
				(justify mirror)
			)
		)
		(property "Value" ""
			(at 0 0 90)
			(layer "B.Fab")
			(effects
				(font
					(size 1.27 1.27)
				)
				(justify mirror)
			)
		)
		(duplicate_pad_numbers_are_jumpers no)
		(fp_line
			(start 0.7874 -0.4064)
			(end -0.7874 -0.4064)
			(stroke
				(width 0.1524)
				(type default)
			)
			(layer "B.SilkS")
		)
		(fp_line
			(start -0.7874 -0.4064)
			(end -0.7874 0.4064)
			(stroke
				(width 0.1524)
				(type default)
			)
			(layer "B.SilkS")
		)
		(fp_line
			(start 0.7874 0.4064)
			(end 0.7874 -0.4064)
			(stroke
				(width 0.1524)
				(type default)
			)
			(layer "B.SilkS")
		)
		(fp_line
			(start -0.7874 0.4064)
			(end 0.7874 0.4064)
			(stroke
				(width 0.1524)
				(type default)
			)
			(layer "B.SilkS")
		)
		(fp_line
			(start 0.67945 -0.305054)
			(end 0.12065 -0.305054)
			(stroke
				(width 0.1)
				(type default)
			)
			(layer "B.Fab")
		)
		(fp_line
			(start 0.12065 -0.305054)
			(end 0.12065 -0.2794)
			(stroke
				(width 0.1)
				(type default)
			)
			(layer "B.Fab")
		)
		(fp_line
			(start -0.12065 -0.3048)
			(end -0.67945 -0.3048)
			(stroke
				(width 0.1)
				(type default)
			)
			(layer "B.Fab")
		)
		(fp_line
			(start -0.67945 -0.3048)
			(end -0.67945 0.3048)
			(stroke
				(width 0.1)
				(type default)
			)
			(layer "B.Fab")
		)
		(fp_line
			(start 0.12065 -0.2794)
			(end -0.12065 -0.2794)
			(stroke
				(width 0.1)
				(type default)
			)
			(layer "B.Fab")
		)
		(fp_line
			(start -0.12065 -0.2794)
			(end -0.12065 -0.3048)
			(stroke
				(width 0.1)
				(type default)
			)
			(layer "B.Fab")
		)
		(fp_line
			(start 0.12065 0.2794)
			(end 0.12065 0.3048)
			(stroke
				(width 0.1)
				(type default)
			)
			(layer "B.Fab")
		)
		(fp_line
			(start -0.120396 0.2794)
			(end 0.12065 0.2794)
			(stroke
				(width 0.1)
				(type default)
			)
			(layer "B.Fab")
		)
		(fp_line
			(start 0.67945 0.3048)
			(end 0.67945 -0.305054)
			(stroke
				(width 0.1)
				(type default)
			)
			(layer "B.Fab")
		)
		(fp_line
			(start 0.12065 0.3048)
			(end 0.67945 0.3048)
			(stroke
				(width 0.1)
				(type default)
			)
			(layer "B.Fab")
		)
		(fp_line
			(start -0.120396 0.3048)
			(end -0.120396 0.2794)
			(stroke
				(width 0.1)
				(type default)
			)
			(layer "B.Fab")
		)
		(fp_line
			(start -0.67945 0.3048)
			(end -0.120396 0.3048)
			(stroke
				(width 0.1)
				(type default)
			)
			(layer "B.Fab")
		)
		(pad "1" smd circle
			(at 0.40005 0 270)
			(size 0 0)
			(layers "B.Cu" "B.Mask" "B.Paste")
			(net "LED_PWRGD_PVDDCR_CPU0_P0_R")
		)
		(pad "2" smd circle
			(at -0.40005 0 270)
			(size 0 0)
			(layers "B.Cu" "B.Mask" "B.Paste")
			(net "P3V3_AUX")
		)
	)
	(footprint ""
		(layer "B.Cu")
		(at 20.919186 -193.996564)
		(property "Reference" "C156"
			(at 0 0 0)
			(layer "B.SilkS")
			(hide yes)
			(effects
				(font
					(size 1.27 1.27)
				)
				(justify mirror)
			)
		)
		(property "Value" ""
			(at 0 0 0)
			(layer "B.Fab")
			(effects
				(font
					(size 1.27 1.27)
				)
				(justify mirror)
			)
		)
		(duplicate_pad_numbers_are_jumpers no)
		(fp_line
			(start -0.7874 -0.4064)
			(end -0.7874 0.4064)
			(stroke
				(width 0.1524)
				(type default)
			)
			(layer "B.SilkS")
		)
		(fp_line
			(start -0.7874 0.4064)
			(end 0.7874 0.4064)
			(stroke
				(width 0.1524)
				(type default)
			)
			(layer "B.SilkS")
		)
		(fp_line
			(start 0.7874 -0.4064)
			(end -0.7874 -0.4064)
			(stroke
				(width 0.1524)
				(type default)
			)
			(layer "B.SilkS")
		)
		(fp_line
			(start 0.7874 0.4064)
			(end 0.7874 -0.4064)
			(stroke
				(width 0.1524)
				(type default)
			)
			(layer "B.SilkS")
		)
		(fp_line
			(start -0.67945 -0.3048)
			(end -0.67945 0.3048)
			(stroke
				(width 0.1)
				(type default)
			)
			(layer "B.Fab")
		)
		(fp_line
			(start -0.67945 0.3048)
			(end -0.120396 0.3048)
			(stroke
				(width 0.1)
				(type default)
			)
			(layer "B.Fab")
		)
		(fp_line
			(start -0.12065 -0.3048)
			(end -0.67945 -0.3048)
			(stroke
				(width 0.1)
				(type default)
			)
			(layer "B.Fab")
		)
		(fp_line
			(start -0.12065 -0.2794)
			(end -0.12065 -0.3048)
			(stroke
				(width 0.1)
				(type default)
			)
			(layer "B.Fab")
		)
		(fp_line
			(start -0.120396 0.2794)
			(end 0.12065 0.2794)
			(stroke
				(width 0.1)
				(type default)
			)
			(layer "B.Fab")
		)
		(fp_line
			(start -0.120396 0.3048)
			(end -0.120396 0.2794)
			(stroke
				(width 0.1)
				(type default)
			)
			(layer "B.Fab")
		)
		(fp_line
			(start 0.12065 -0.305054)
			(end 0.12065 -0.2794)
			(stroke
				(width 0.1)
				(type default)
			)
			(layer "B.Fab")
		)
		(fp_line
			(start 0.12065 -0.2794)
			(end -0.12065 -0.2794)
			(stroke
				(width 0.1)
				(type default)
			)
			(layer "B.Fab")
		)
		(fp_line
			(start 0.12065 0.2794)
			(end 0.12065 0.3048)
			(stroke
				(width 0.1)
				(type default)
			)
			(layer "B.Fab")
		)
		(fp_line
			(start 0.12065 0.3048)
			(end 0.67945 0.3048)
			(stroke
				(width 0.1)
				(type default)
			)
			(layer "B.Fab")
		)
		(fp_line
			(start 0.67945 -0.305054)
			(end 0.12065 -0.305054)
			(stroke
				(width 0.1)
				(type default)
			)
			(layer "B.Fab")
		)
		(fp_line
			(start 0.67945 0.3048)
			(end 0.67945 -0.305054)
			(stroke
				(width 0.1)
				(type default)
			)
			(layer "B.Fab")
		)
		(pad "1" smd circle
			(at 0.40005 0 180)
			(size 0 0)
			(layers "B.Cu" "B.Mask" "B.Paste")
			(net "P3V3_AUX")
		)
		(pad "2" smd circle
			(at -0.40005 0 180)
			(size 0 0)
			(layers "B.Cu" "B.Mask" "B.Paste")
			(net "GND")
		)
	)
)
